(kicad_pcb
	(version 20260206)
	(generator "pcbnew")
	(generator_version "10.0")
	(general
		(thickness 1.6)
		(legacy_teardrops no)
	)
	(paper "A4")
	(title_block
		(title "Wiwynn_Tioga_Pass_MB.brd")
		(comment 1 "Tioga Pass / footprint 1664 of 4770 (U7C1), pads 1151-1265 of 1310")
	)
	(layers
		(0 "F.Cu" signal "TOP")
		(4 "In1.Cu" signal "L2GND")
		(6 "In2.Cu" signal "L3")
		(8 "In3.Cu" signal "L4GND")
		(10 "In4.Cu" signal "L5")
		(12 "In5.Cu" signal "L6GND")
		(14 "In6.Cu" signal "L7VCC")
		(16 "In7.Cu" signal "L8VCC")
		(18 "In8.Cu" signal "L9GND")
		(20 "In9.Cu" signal "L10")
		(22 "In10.Cu" signal "L11GND")
		(24 "In11.Cu" signal "L12")
		(26 "In12.Cu" signal "L13GND")
		(2 "B.Cu" signal "BOTTOM")
		(9 "F.Adhes" user "F.Adhesive")
		(11 "B.Adhes" user "B.Adhesive")
		(13 "F.Paste" user "Package Geometry/Pastemask Top")
		(15 "B.Paste" user "Package Geometry/Pastemask Bottom")
		(5 "F.SilkS" user "Ref Des/Silkscreen Top")
		(7 "B.SilkS" user "Ref Des/Silkscreen Bottom")
		(1 "F.Mask" user "Board Geometry/Soldermask Top")
		(3 "B.Mask" user "Board Geometry/Soldermask Bottom")
		(17 "Dwgs.User" user "User.Drawings")
		(19 "Cmts.User" user "User.Comments")
		(21 "Eco1.User" user "User.Eco1")
		(23 "Eco2.User" user "User.Eco2")
		(25 "Edge.Cuts" user "Board Geometry/Outline")
		(27 "Margin" user)
		(31 "F.CrtYd" user "Package Geometry/Place Bound Top")
		(29 "B.CrtYd" user "Package Geometry/Place Bound Bottom")
		(35 "F.Fab" user "Ref Des/Assembly Top")
		(33 "B.Fab" user "Ref Des/Assembly Bottom")
	)
	(footprint ""
		(layer "F.Cu")
		(at 387.985 -109.855 90)
		(property "Reference" "U7C1"
			(at 17.75333 -13.335 0)
			(unlocked yes)
			(layer "F.SilkS")
			(effects
				(font
					(size 0.7874 0.5842)
					(thickness 0.1524)
				)
				(justify left)
			)
		)
		(property "Value" ""
			(at 0 0 90)
			(layer "F.Fab")
			(effects
				(font
					(size 1.27 1.27)
				)
			)
		)
		(duplicate_pad_numbers_are_jumpers no)
		(pad "N31" smd circle
			(at -2.57556 -8.17245)
			(size 0.381 0.381)
			(layers "F.Cu" "F.Mask" "F.Paste")
			(net "GND")
		)
		(pad "N35" smd circle
			(at -0.85852 -8.17245)
			(size 0.381 0.381)
			(layers "F.Cu" "F.Mask" "F.Paste")
			(net "GND")
		)
		(pad "N38" smd circle
			(at 0.85852 -8.17245)
			(size 0.381 0.381)
			(layers "F.Cu" "F.Mask" "F.Paste")
			(net "GND")
		)
		(pad "N42" smd circle
			(at 2.57556 -8.17245)
			(size 0.381 0.381)
			(layers "F.Cu" "F.Mask" "F.Paste")
			(net "GND")
		)
		(pad "N46" smd circle
			(at 4.2926 -8.17245)
			(size 0.381 0.381)
			(layers "F.Cu" "F.Mask" "F.Paste")
			(net "GND")
		)
		(pad "N50" smd circle
			(at 6.00964 -8.17245)
			(size 0.381 0.381)
			(layers "F.Cu" "F.Mask" "F.Paste")
			(net "GND")
		)
		(pad "N54" smd circle
			(at 7.72668 -8.17245)
			(size 0.381 0.381)
			(layers "F.Cu" "F.Mask" "F.Paste")
			(net "DMI_CPU0_PCH_RX_DP<3>")
		)
		(pad "N58" smd circle
			(at 9.44372 -8.17245)
			(size 0.381 0.381)
			(layers "F.Cu" "F.Mask" "F.Paste")
			(net "P3E_CPU0_PE1_PCH_RXN<4>")
		)
		(pad "N61" smd circle
			(at 11.16076 -8.17245)
			(size 0.381 0.381)
			(layers "F.Cu" "F.Mask" "F.Paste")
			(net "P3E_CPU0_PE1_PCH_RXN<5>")
		)
		(pad "N65" smd circle
			(at 12.8778 -8.17245)
			(size 0.381 0.381)
			(layers "F.Cu" "F.Mask" "F.Paste")
			(net "P3E_CPU0_PE1_PCH_R_RXN<10>")
		)
		(pad "N68" smd circle
			(at 14.649958 -7.999984)
			(size 0.3048 0.3048)
			(layers "F.Cu" "F.Mask" "F.Paste")
			(net "GND")
		)
		(pad "N70" smd circle
			(at 15.48003 -7.999984)
			(size 0.3048 0.3048)
			(layers "F.Cu" "F.Mask" "F.Paste")
			(net "SATA6G_PCH_PCIE_UP_SATA_TXN<5>")
		)
		(pad "N72" smd oval
			(at 16.310102 -7.999984 180)
			(size 0.254 0.3302)
			(layers "F.Cu" "F.Mask" "F.Paste")
			(net "SATA6G_PCH_PCIE_UP_SATA_TXP<5>")
		)
		(pad "P2" smd circle
			(at -15.895066 -7.500112 180)
			(size 0.3048 0.3048)
			(layers "F.Cu" "F.Mask" "F.Paste")
			(net "IRQ_LPC_SERIRQ_N")
		)
		(pad "P4" smd circle
			(at -15.064994 -7.500112 180)
			(size 0.3048 0.3048)
			(layers "F.Cu" "F.Mask" "F.Paste")
			(net "LPC_LFRAME_N_CS0_N")
		)
		(pad "P7" smd circle
			(at -13.73632 -7.67715)
			(size 0.381 0.381)
			(layers "F.Cu" "F.Mask" "F.Paste")
			(net "FM_SLP_SUS_N")
		)
		(pad "P11" smd circle
			(at -12.01928 -7.67715)
			(size 0.381 0.381)
			(layers "F.Cu" "F.Mask" "F.Paste")
			(net "RST_RTCRST_N")
		)
		(pad "P15" smd circle
			(at -10.30224 -7.67715)
			(size 0.381 0.381)
			(layers "F.Cu" "F.Mask" "F.Paste")
			(net "RST_RSMRST_N")
		)
		(pad "P18" smd circle
			(at -8.5852 -7.67715)
			(size 0.381 0.381)
			(layers "F.Cu" "F.Mask" "F.Paste")
			(net "TP_PCH_HDA_BCLK")
		)
		(pad "P22" smd circle
			(at -6.86816 -7.67715)
			(size 0.381 0.381)
			(layers "F.Cu" "F.Mask" "F.Paste")
			(net "TP_PCH_RSVD45")
		)
		(pad "P26" smd circle
			(at -5.15112 -7.67715)
			(size 0.381 0.381)
			(layers "F.Cu" "F.Mask" "F.Paste")
			(net "TP_PCH_RSVD53")
		)
		(pad "P29" smd circle
			(at -3.43408 -7.67715)
			(size 0.381 0.381)
			(layers "F.Cu" "F.Mask" "F.Paste")
			(net "TP_PCH_RSVD31")
		)
		(pad "P33" smd circle
			(at -1.71704 -7.67715)
			(size 0.381 0.381)
			(layers "F.Cu" "F.Mask" "F.Paste")
			(net "TP_PCH_RSVD29")
		)
		(pad "P37" smd circle
			(at 0 -7.67715)
			(size 0.381 0.381)
			(layers "F.Cu" "F.Mask" "F.Paste")
			(net "TP_PCH_RSVD4")
		)
		(pad "P40" smd circle
			(at 1.71704 -7.67715)
			(size 0.381 0.381)
			(layers "F.Cu" "F.Mask" "F.Paste")
			(net "TP_PCH_RSVD23")
		)
		(pad "P44" smd circle
			(at 3.43408 -7.67715)
			(size 0.381 0.381)
			(layers "F.Cu" "F.Mask" "F.Paste")
			(net "TP_PCH_RSVD24")
		)
		(pad "P48" smd circle
			(at 5.15112 -7.67715)
			(size 0.381 0.381)
			(layers "F.Cu" "F.Mask" "F.Paste")
			(net "TP_PCH_RSVD25")
		)
		(pad "P52" smd circle
			(at 6.86816 -7.67715)
			(size 0.381 0.381)
			(layers "F.Cu" "F.Mask" "F.Paste")
			(net "DMI_CPU0_PCH_RX_DN<3>")
		)
		(pad "P56" smd circle
			(at 8.5852 -7.67715)
			(size 0.381 0.381)
			(layers "F.Cu" "F.Mask" "F.Paste")
			(net "P3E_CPU0_PE1_PCH_RXN<1>")
		)
		(pad "P59" smd circle
			(at 10.30224 -7.67715)
			(size 0.381 0.381)
			(layers "F.Cu" "F.Mask" "F.Paste")
			(net "P3E_CPU0_PE1_PCH_RXN<7>")
		)
		(pad "P63" smd circle
			(at 12.01928 -7.67715)
			(size 0.381 0.381)
			(layers "F.Cu" "F.Mask" "F.Paste")
			(net "GND")
		)
		(pad "P66" smd circle
			(at 13.73632 -7.67715)
			(size 0.381 0.381)
			(layers "F.Cu" "F.Mask" "F.Paste")
			(net "P3E_CPU0_PE1_PCH_R_RXP<10>")
		)
		(pad "P69" smd circle
			(at 15.064994 -7.500112)
			(size 0.3048 0.3048)
			(layers "F.Cu" "F.Mask" "F.Paste")
			(net "SATA6G_PCH_PCIE_UP_SATA_TXN<4>")
		)
		(pad "P71" smd circle
			(at 15.895066 -7.500112)
			(size 0.3048 0.3048)
			(layers "F.Cu" "F.Mask" "F.Paste")
			(net "SATA6G_PCH_PCIE_UP_SATA_TXP<4>")
		)
		(pad "R1" smd oval
			(at -16.310102 -6.999986 180)
			(size 0.254 0.3302)
			(layers "F.Cu" "F.Mask" "F.Paste")
			(net "PU_IRQ_PCH_SCI_WHEA_N")
		)
		(pad "R3" smd circle
			(at -15.48003 -6.999986 180)
			(size 0.3048 0.3048)
			(layers "F.Cu" "F.Mask" "F.Paste")
			(net "CLK_24M_BMC_LPC_R")
		)
		(pad "R5" smd circle
			(at -14.649958 -6.999986 180)
			(size 0.3048 0.3048)
			(layers "F.Cu" "F.Mask" "F.Paste")
			(net "GND")
		)
		(pad "R9" smd circle
			(at -12.8778 -7.18185)
			(size 0.381 0.381)
			(layers "F.Cu" "F.Mask" "F.Paste")
			(net "PWRGD_CPUPWRGD_GTL")
		)
		(pad "R13" smd circle
			(at -11.16076 -7.18185)
			(size 0.381 0.381)
			(layers "F.Cu" "F.Mask" "F.Paste")
			(net "TP_CPU_PCH_TRIGGER_OUT")
		)
		(pad "R17" smd circle
			(at -9.44372 -7.18185)
			(size 0.381 0.381)
			(layers "F.Cu" "F.Mask" "F.Paste")
			(net "PWRGD_PCH_PWROK")
		)
		(pad "R20" smd circle
			(at -7.72668 -7.18185)
			(size 0.381 0.381)
			(layers "F.Cu" "F.Mask" "F.Paste")
			(net "TP_PCH_DISPA_SDI")
		)
		(pad "R24" smd circle
			(at -6.00964 -7.18185)
			(size 0.381 0.381)
			(layers "F.Cu" "F.Mask" "F.Paste")
			(net "TP_PCH_RSVD54")
		)
		(pad "R27" smd circle
			(at -4.2926 -7.18185)
			(size 0.381 0.381)
			(layers "F.Cu" "F.Mask" "F.Paste")
			(net "GND")
		)
		(pad "R31" smd circle
			(at -2.57556 -7.18185)
			(size 0.381 0.381)
			(layers "F.Cu" "F.Mask" "F.Paste")
			(net "TP_PCH_RSVD30")
		)
		(pad "R35" smd circle
			(at -0.85852 -7.18185)
			(size 0.381 0.381)
			(layers "F.Cu" "F.Mask" "F.Paste")
			(net "TP_PCH_RSVD28")
		)
		(pad "R38" smd circle
			(at 0.85852 -7.18185)
			(size 0.381 0.381)
			(layers "F.Cu" "F.Mask" "F.Paste")
			(net "GND")
		)
		(pad "R42" smd circle
			(at 2.57556 -7.18185)
			(size 0.381 0.381)
			(layers "F.Cu" "F.Mask" "F.Paste")
			(net "P1V05_PCH_STBY")
		)
		(pad "R46" smd circle
			(at 4.2926 -7.18185)
			(size 0.381 0.381)
			(layers "F.Cu" "F.Mask" "F.Paste")
			(net "P1V05_PCH_STBY")
		)
		(pad "R50" smd circle
			(at 6.00964 -7.18185)
			(size 0.381 0.381)
			(layers "F.Cu" "F.Mask" "F.Paste")
			(net "GND")
		)
		(pad "R54" smd circle
			(at 7.72668 -7.18185)
			(size 0.381 0.381)
			(layers "F.Cu" "F.Mask" "F.Paste")
			(net "GND")
		)
		(pad "R58" smd circle
			(at 9.44372 -7.18185)
			(size 0.381 0.381)
			(layers "F.Cu" "F.Mask" "F.Paste")
			(net "GND")
		)
		(pad "R61" smd circle
			(at 11.16076 -7.18185)
			(size 0.381 0.381)
			(layers "F.Cu" "F.Mask" "F.Paste")
			(net "P3E_CPU0_PE1_PCH_RXP<7>")
		)
		(pad "R65" smd circle
			(at 12.8778 -7.18185)
			(size 0.381 0.381)
			(layers "F.Cu" "F.Mask" "F.Paste")
			(net "P3E_CPU0_PE1_PCH_R_RXN<12>")
		)
		(pad "R68" smd circle
			(at 14.649958 -6.999986)
			(size 0.3048 0.3048)
			(layers "F.Cu" "F.Mask" "F.Paste")
			(net "GND")
		)
		(pad "R70" smd circle
			(at 15.48003 -6.999986)
			(size 0.3048 0.3048)
			(layers "F.Cu" "F.Mask" "F.Paste")
			(net "SATA6G_PCH_PCIE_UP_SATA_TXN<3>")
		)
		(pad "R72" smd oval
			(at 16.310102 -6.999986 180)
			(size 0.254 0.3302)
			(layers "F.Cu" "F.Mask" "F.Paste")
			(net "SATA6G_PCH_PCIE_UP_SATA_TXP<3>")
		)
		(pad "T2" smd circle
			(at -15.895066 -6.500114 180)
			(size 0.3048 0.3048)
			(layers "F.Cu" "F.Mask" "F.Paste")
			(net "FM_UART_PRES_N")
		)
		(pad "T4" smd circle
			(at -15.064994 -6.500114 180)
			(size 0.3048 0.3048)
			(layers "F.Cu" "F.Mask" "F.Paste")
			(net "FM_MB_SLOT_ID0")
		)
		(pad "T7" smd circle
			(at -13.73632 -6.68655)
			(size 0.381 0.381)
			(layers "F.Cu" "F.Mask" "F.Paste")
			(net "GND")
		)
		(pad "T11" smd circle
			(at -12.01928 -6.68655)
			(size 0.381 0.381)
			(layers "F.Cu" "F.Mask" "F.Paste")
			(net "GND")
		)
		(pad "T15" smd circle
			(at -10.30224 -6.68655)
			(size 0.381 0.381)
			(layers "F.Cu" "F.Mask" "F.Paste")
			(net "GND")
		)
		(pad "T18" smd circle
			(at -8.5852 -6.68655)
			(size 0.381 0.381)
			(layers "F.Cu" "F.Mask" "F.Paste")
			(net "GND")
		)
		(pad "T22" smd circle
			(at -6.86816 -6.68655)
			(size 0.381 0.381)
			(layers "F.Cu" "F.Mask" "F.Paste")
			(net "GND")
		)
		(pad "T26" smd circle
			(at -5.15112 -6.68655)
			(size 0.381 0.381)
			(layers "F.Cu" "F.Mask" "F.Paste")
			(net "GND")
		)
		(pad "T29" smd circle
			(at -3.43408 -6.68655)
			(size 0.381 0.381)
			(layers "F.Cu" "F.Mask" "F.Paste")
			(net "GND")
		)
		(pad "T33" smd circle
			(at -1.71704 -6.68655)
			(size 0.381 0.381)
			(layers "F.Cu" "F.Mask" "F.Paste")
			(net "GND")
		)
		(pad "T37" smd circle
			(at 0 -6.68655)
			(size 0.381 0.381)
			(layers "F.Cu" "F.Mask" "F.Paste")
			(net "GND")
		)
		(pad "T40" smd circle
			(at 1.71704 -6.68655)
			(size 0.381 0.381)
			(layers "F.Cu" "F.Mask" "F.Paste")
			(net "GND")
		)
		(pad "T44" smd circle
			(at 3.43408 -6.68655)
			(size 0.381 0.381)
			(layers "F.Cu" "F.Mask" "F.Paste")
			(net "P1V05_PCH_STBY")
		)
		(pad "T48" smd circle
			(at 5.15112 -6.68655)
			(size 0.381 0.381)
			(layers "F.Cu" "F.Mask" "F.Paste")
			(net "GND")
		)
		(pad "T52" smd circle
			(at 6.86816 -6.68655)
			(size 0.381 0.381)
			(layers "F.Cu" "F.Mask" "F.Paste")
			(net "GND")
		)
		(pad "T56" smd circle
			(at 8.5852 -6.68655)
			(size 0.381 0.381)
			(layers "F.Cu" "F.Mask" "F.Paste")
			(net "GND")
		)
		(pad "T59" smd circle
			(at 10.30224 -6.68655)
			(size 0.381 0.381)
			(layers "F.Cu" "F.Mask" "F.Paste")
			(net "P3E_CPU0_PE1_PCH_R_RXN<11>")
		)
		(pad "T63" smd circle
			(at 12.01928 -6.68655)
			(size 0.381 0.381)
			(layers "F.Cu" "F.Mask" "F.Paste")
			(net "P3E_CPU0_PE1_PCH_R_RXN<13>")
		)
		(pad "T66" smd circle
			(at 13.73632 -6.68655)
			(size 0.381 0.381)
			(layers "F.Cu" "F.Mask" "F.Paste")
			(net "GND")
		)
		(pad "T69" smd circle
			(at 15.064994 -6.500114)
			(size 0.3048 0.3048)
			(layers "F.Cu" "F.Mask" "F.Paste")
			(net "SATA6G_PCH_PCIE_UP_SATA_TXN<2>")
		)
		(pad "T71" smd circle
			(at 15.895066 -6.500114)
			(size 0.3048 0.3048)
			(layers "F.Cu" "F.Mask" "F.Paste")
			(net "SATA6G_PCH_PCIE_UP_SATA_TXP<2>")
		)
		(pad "U9" smd circle
			(at -12.8778 -6.19125)
			(size 0.381 0.381)
			(layers "F.Cu" "F.Mask" "F.Paste")
			(net "PECI_PCH")
		)
		(pad "U13" smd circle
			(at -11.16076 -6.19125)
			(size 0.381 0.381)
			(layers "F.Cu" "F.Mask" "F.Paste")
			(net "H_PM_SYNC1_GTL_R")
		)
		(pad "U17" smd circle
			(at -9.44372 -6.19125)
			(size 0.381 0.381)
			(layers "F.Cu" "F.Mask" "F.Paste")
			(net "TP_PLTRST_CPU_N")
		)
		(pad "U20" smd circle
			(at -7.72668 -6.19125)
			(size 0.381 0.381)
			(layers "F.Cu" "F.Mask" "F.Paste")
			(net "TP_PCH_DISPA_BCLK")
		)
		(pad "U24" smd circle
			(at -6.00964 -6.19125)
			(size 0.381 0.381)
			(layers "F.Cu" "F.Mask" "F.Paste")
			(net "FM_FLASH_DESC_OVERRIDE")
		)
		(pad "U27" smd circle
			(at -4.2926 -6.19125)
			(size 0.381 0.381)
			(layers "F.Cu" "F.Mask" "F.Paste")
			(net "PVNN_PCH_STBY")
		)
		(pad "U31" smd circle
			(at -2.57556 -6.19125)
			(size 0.381 0.381)
			(layers "F.Cu" "F.Mask" "F.Paste")
			(net "PVNN_PCH_STBY")
		)
		(pad "U35" smd circle
			(at -0.85852 -6.19125)
			(size 0.381 0.381)
			(layers "F.Cu" "F.Mask" "F.Paste")
			(net "PVNN_PCH_STBY")
		)
		(pad "U38" smd circle
			(at 0.85852 -6.19125)
			(size 0.381 0.381)
			(layers "F.Cu" "F.Mask" "F.Paste")
			(net "PVNN_PCH_STBY")
		)
		(pad "U42" smd circle
			(at 2.57556 -6.19125)
			(size 0.381 0.381)
			(layers "F.Cu" "F.Mask" "F.Paste")
			(net "GND")
		)
		(pad "U46" smd circle
			(at 4.2926 -6.19125)
			(size 0.381 0.381)
			(layers "F.Cu" "F.Mask" "F.Paste")
			(net "P1V05_PCH_STBY")
		)
		(pad "U50" smd circle
			(at 6.00964 -6.19125)
			(size 0.381 0.381)
			(layers "F.Cu" "F.Mask" "F.Paste")
			(net "P1V05_PCH_STBY")
		)
		(pad "U54" smd circle
			(at 7.72668 -6.19125)
			(size 0.381 0.381)
			(layers "F.Cu" "F.Mask" "F.Paste")
			(net "XDP_PREQ_N")
		)
		(pad "U58" smd circle
			(at 9.44372 -6.19125)
			(size 0.381 0.381)
			(layers "F.Cu" "F.Mask" "F.Paste")
			(net "GND")
		)
		(pad "U61" smd circle
			(at 11.16076 -6.19125)
			(size 0.381 0.381)
			(layers "F.Cu" "F.Mask" "F.Paste")
			(net "P3E_CPU0_PE1_PCH_R_RXP<13>")
		)
		(pad "U65" smd circle
			(at 12.8778 -6.19125)
			(size 0.381 0.381)
			(layers "F.Cu" "F.Mask" "F.Paste")
			(net "P3E_CPU0_PE1_PCH_R_RXP<12>")
		)
		(pad "V1" smd oval
			(at -16.310102 -5.999988 180)
			(size 0.254 0.3302)
			(layers "F.Cu" "F.Mask" "F.Paste")
			(net "FM_BMC_READY_R_N")
		)
		(pad "V3" smd circle
			(at -15.48003 -5.999988 180)
			(size 0.3048 0.3048)
			(layers "F.Cu" "F.Mask" "F.Paste")
			(net "FM_ME_RECOVER_N")
		)
		(pad "V5" smd circle
			(at -14.649958 -5.999988 180)
			(size 0.3048 0.3048)
			(layers "F.Cu" "F.Mask" "F.Paste")
			(net "GND")
		)
		(pad "V7" smd circle
			(at -13.73632 -5.69595)
			(size 0.381 0.381)
			(layers "F.Cu" "F.Mask" "F.Paste")
			(net "TP_PM_SYNC_GTL")
		)
		(pad "V11" smd circle
			(at -12.01928 -5.69595)
			(size 0.381 0.381)
			(layers "F.Cu" "F.Mask" "F.Paste")
			(net "TP_PCH_RSVD3")
		)
		(pad "V15" smd circle
			(at -10.30224 -5.69595)
			(size 0.381 0.381)
			(layers "F.Cu" "F.Mask" "F.Paste")
			(net "FM_PCH_LVC1_THERMTRIP_N")
		)
		(pad "V18" smd circle
			(at -8.5852 -5.69595)
			(size 0.381 0.381)
			(layers "F.Cu" "F.Mask" "F.Paste")
			(net "TP_PCH_HDA_SDI_1")
		)
		(pad "V22" smd circle
			(at -6.86816 -5.69595)
			(size 0.381 0.381)
			(layers "F.Cu" "F.Mask" "F.Paste")
			(net "TP_PCH_DISPA_SDO")
		)
		(pad "V26" smd circle
			(at -5.15112 -5.696458)
			(size 0.381 0.381)
			(layers "F.Cu" "F.Mask" "F.Paste")
			(net "GND")
		)
		(pad "V29" smd circle
			(at -3.43408 -5.69595)
			(size 0.381 0.381)
			(layers "F.Cu" "F.Mask" "F.Paste")
			(net "PVNN_PCH_STBY")
		)
		(pad "V33" smd circle
			(at -1.71704 -5.69595)
			(size 0.381 0.381)
			(layers "F.Cu" "F.Mask" "F.Paste")
			(net "PVNN_PCH_STBY")
		)
		(pad "V37" smd circle
			(at 0 -5.69595)
			(size 0.381 0.381)
			(layers "F.Cu" "F.Mask" "F.Paste")
			(net "VSENSE_PVNN_PCH_STBY_QAT")
		)
		(pad "V40" smd circle
			(at 1.71704 -5.69595)
			(size 0.381 0.381)
			(layers "F.Cu" "F.Mask" "F.Paste")
			(net "PVNN_PCH_STBY")
		)
		(pad "V44" smd circle
			(at 3.43408 -5.69595)
			(size 0.381 0.381)
			(layers "F.Cu" "F.Mask" "F.Paste")
			(net "P1V05_PCH_STBY")
		)
		(pad "V48" smd circle
			(at 5.15112 -5.696458)
			(size 0.381 0.381)
			(layers "F.Cu" "F.Mask" "F.Paste")
			(net "GND")
		)
		(pad "V52" smd circle
			(at 6.86816 -5.69595)
			(size 0.381 0.381)
			(layers "F.Cu" "F.Mask" "F.Paste")
			(net "GND")
		)
		(pad "V56" smd circle
			(at 8.5852 -5.69595)
			(size 0.381 0.381)
			(layers "F.Cu" "F.Mask" "F.Paste")
			(net "TP_PCH_RSVD33")
		)
		(pad "V59" smd circle
			(at 10.30224 -5.69595)
			(size 0.381 0.381)
			(layers "F.Cu" "F.Mask" "F.Paste")
			(net "P3E_CPU0_PE1_PCH_R_RXP<11>")
		)
		(pad "V63" smd circle
			(at 12.01928 -5.69595)
			(size 0.381 0.381)
			(layers "F.Cu" "F.Mask" "F.Paste")
			(net "P3E_CPU0_PE1_PCH_R_RXP<14>")
		)
		(pad "V66" smd circle
			(at 13.73632 -5.69595)
			(size 0.381 0.381)
			(layers "F.Cu" "F.Mask" "F.Paste")
			(net "GND")
		)
		(pad "V68" smd circle
			(at 14.649958 -5.999988)
			(size 0.3048 0.3048)
			(layers "F.Cu" "F.Mask" "F.Paste")
			(net "GND")
		)
		(pad "V70" smd circle
			(at 15.48003 -5.999988)
			(size 0.3048 0.3048)
			(layers "F.Cu" "F.Mask" "F.Paste")
			(net "SATA6G_PCH_PCIE_UP_SATA_TXN<1>")
		)
	)
)
